(kicad_pcb
	(version 20241229)
	(generator "pcbnew")
	(generator_version "9.0")
	(general
		(thickness 1.63)
		(legacy_teardrops no)
	)
	(paper "A4")
	(title_block
		(title "CM4 Baseboard")
		(date "2026-01-05")
		(rev "1.1.1")
		(company "Antmicro Ltd")
		(comment 1 "www.antmicro.com")
		(comment 9 "footprints 267-272 of 506")
	)
	(layers
		(0 "F.Cu" signal)
		(4 "In1.Cu" power)
		(6 "In2.Cu" power)
		(8 "In3.Cu" signal)
		(10 "In4.Cu" signal)
		(2 "B.Cu" signal)
		(9 "F.Adhes" user "F.Adhesive")
		(11 "B.Adhes" user "B.Adhesive")
		(13 "F.Paste" user)
		(15 "B.Paste" user)
		(5 "F.SilkS" user "F.Silkscreen")
		(7 "B.SilkS" user "B.Silkscreen")
		(1 "F.Mask" user)
		(3 "B.Mask" user)
		(17 "Dwgs.User" user "User.Drawings")
		(19 "Cmts.User" user "User.Comments")
		(21 "Eco1.User" user "User.Eco1")
		(23 "Eco2.User" user "User.Eco2")
		(25 "Edge.Cuts" user)
		(27 "Margin" user)
		(31 "F.CrtYd" user "F.Courtyard")
		(29 "B.CrtYd" user "B.Courtyard")
		(35 "F.Fab" user)
		(33 "B.Fab" user)
	)
	(footprint "antmicro-footprints:R_0402_1005Metric"
		(layer "F.Cu")
		(at 58.992962 176.3255 180)
		(descr "Resistor SMD 0402")
		(tags "resistor SMD 0402")
		(property "Reference" "R810"
			(at -1.507038 1.3255 0)
			(layer "F.SilkS")
			(effects
				(font
					(size 0.7 0.7)
					(thickness 0.15)
				)
				(justify right top)
			)
		)
		(property "Value" "R_0R_0402"
			(at -1.011843 1.772046 0)
			(layer "F.Fab")
			(effects
				(font
					(size 0.7 0.7)
					(thickness 0.15)
				)
				(justify right top)
			)
		)
		(property "Datasheet" "https://industrial.panasonic.com/cdbs/www-data/pdf/RDA0000/AOA0000C301.pdf"
			(at 0 0 0)
			(layer "F.Fab")
			(hide yes)
			(effects
				(font
					(size 1.27 1.27)
					(thickness 0.15)
				)
			)
		)
		(property "Description" "SMD Chip Resistor, Jumper, 0 ohm, 100 mW, 0402 [1005 Metric], Thick Film, General Purpose"
			(at 0 0 0)
			(layer "F.Fab")
			(hide yes)
			(effects
				(font
					(size 1.27 1.27)
					(thickness 0.15)
				)
			)
		)
		(property "MPN" "ERJ2GE0R00X"
			(at 0 0 180)
			(unlocked yes)
			(layer "F.Fab")
			(hide yes)
			(effects
				(font
					(size 1 1)
					(thickness 0.15)
				)
			)
		)
		(property "Manufacturer" "Panasonic"
			(at 0 0 180)
			(unlocked yes)
			(layer "F.Fab")
			(hide yes)
			(effects
				(font
					(size 1 1)
					(thickness 0.15)
				)
			)
		)
		(property "License" "Apache-2.0"
			(at 0 0 180)
			(unlocked yes)
			(layer "F.Fab")
			(hide yes)
			(effects
				(font
					(size 1 1)
					(thickness 0.15)
				)
			)
		)
		(property "Author" "Antmicro"
			(at 0 0 180)
			(unlocked yes)
			(layer "F.Fab")
			(hide yes)
			(effects
				(font
					(size 1 1)
					(thickness 0.15)
				)
			)
		)
		(property "Val" "0R"
			(at 0 0 180)
			(unlocked yes)
			(layer "F.Fab")
			(hide yes)
			(effects
				(font
					(size 1 1)
					(thickness 0.15)
				)
			)
		)
		(property "Tolerance" "~"
			(at 0 0 180)
			(unlocked yes)
			(layer "F.Fab")
			(hide yes)
			(effects
				(font
					(size 1 1)
					(thickness 0.15)
				)
			)
		)
		(property "Current" "1A"
			(at 0 0 180)
			(unlocked yes)
			(layer "F.Fab")
			(hide yes)
			(effects
				(font
					(size 1 1)
					(thickness 0.15)
				)
			)
		)
		(sheetname "/Peripherals/")
		(sheetfile "peripherals.kicad_sch")
		(attr smd)
		(fp_poly
			(pts
				(xy -0.925 -0.47) (xy 0.925 -0.47) (xy 0.925 0.47) (xy -0.925 0.47)
			)
			(stroke
				(width 0.05)
				(type default)
			)
			(fill no)
			(layer "F.CrtYd")
		)
		(fp_poly
			(pts
				(xy -0.5 -0.25) (xy 0.5 -0.25) (xy 0.5 0.25) (xy -0.5 0.25)
			)
			(stroke
				(width 0.15)
				(type solid)
			)
			(fill no)
			(layer "F.Fab")
		)
		(fp_text user "${REFERENCE}"
			(at -0.95 3.168 0)
			(layer "F.Fab")
			(effects
				(font
					(size 0.7 0.7)
					(thickness 0.15)
				)
				(justify right top)
			)
		)
		(fp_text user "License: Apache-2.0"
			(at -0.949999 5.169 0)
			(layer "F.Fab")
			(effects
				(font
					(size 0.7 0.7)
					(thickness 0.15)
				)
				(justify right top)
			)
		)
		(fp_text user "Author: Antmicro"
			(at -0.95 4.169 0)
			(layer "F.Fab")
			(effects
				(font
					(size 0.7 0.7)
					(thickness 0.15)
				)
				(justify right top)
			)
		)
		(pad "1" smd roundrect
			(at -0.48 0 180)
			(size 0.59 0.64)
			(layers "F.Cu" "F.Mask" "F.Paste")
			(roundrect_rratio 0.25)
			(net 106 "Net-(C814-Pad2)")
			(pintype "passive")
		)
		(pad "2" smd roundrect
			(at 0.48 0 180)
			(size 0.59 0.64)
			(layers "F.Cu" "F.Mask" "F.Paste")
			(roundrect_rratio 0.25)
			(net 319 "Net-(J804-Pad1)")
			(pintype "passive")
		)
	)
	(footprint "antmicro-footprints:C_0402_1005Metric"
		(layer "F.Cu")
		(at 63.617962 175.2255 180)
		(descr "Capacitor SMD 0402")
		(tags "capacitor SMD 0402")
		(property "Reference" "C822"
			(at 13.367962 2.9755 0)
			(layer "F.SilkS")
			(effects
				(font
					(size 0.7 0.7)
					(thickness 0.15)
				)
				(justify right top)
			)
		)
		(property "Value" "C_36p_0402"
			(at -1.022927 2.155213 0)
			(layer "F.Fab")
			(effects
				(font
					(size 0.7 0.7)
					(thickness 0.15)
				)
				(justify right top)
			)
		)
		(property "Datasheet" "https://eu.mouser.com/datasheet/3/5926/1/C0GNP0_Dielectric.pdf"
			(at 0 0 0)
			(layer "F.Fab")
			(hide yes)
			(effects
				(font
					(size 1.27 1.27)
					(thickness 0.15)
				)
			)
		)
		(property "Description" "Multilayer Ceramic Capacitors MLCC, 36 pF, 25V, 0402, C0G, 5%"
			(at 0 0 0)
			(layer "F.Fab")
			(hide yes)
			(effects
				(font
					(size 1.27 1.27)
					(thickness 0.15)
				)
			)
		)
		(property "MPN" "04023A360JAT2A"
			(at 0 0 180)
			(unlocked yes)
			(layer "F.Fab")
			(hide yes)
			(effects
				(font
					(size 1 1)
					(thickness 0.15)
				)
			)
		)
		(property "Manufacturer" "KYOCERA AVX"
			(at 0 0 180)
			(unlocked yes)
			(layer "F.Fab")
			(hide yes)
			(effects
				(font
					(size 1 1)
					(thickness 0.15)
				)
			)
		)
		(property "License" "Apache-2.0"
			(at 0 0 180)
			(unlocked yes)
			(layer "F.Fab")
			(hide yes)
			(effects
				(font
					(size 1 1)
					(thickness 0.15)
				)
			)
		)
		(property "Author" "Antmicro"
			(at 0 0 180)
			(unlocked yes)
			(layer "F.Fab")
			(hide yes)
			(effects
				(font
					(size 1 1)
					(thickness 0.15)
				)
			)
		)
		(property "Val" "36pF"
			(at 0 0 180)
			(unlocked yes)
			(layer "F.Fab")
			(hide yes)
			(effects
				(font
					(size 1 1)
					(thickness 0.15)
				)
			)
		)
		(property "Voltage" "25 V"
			(at 0 0 180)
			(unlocked yes)
			(layer "F.Fab")
			(hide yes)
			(effects
				(font
					(size 1 1)
					(thickness 0.15)
				)
			)
		)
		(property "Dielectric" "C0G (NP0)"
			(at 0 0 180)
			(unlocked yes)
			(layer "F.Fab")
			(hide yes)
			(effects
				(font
					(size 1 1)
					(thickness 0.15)
				)
			)
		)
		(sheetname "/Peripherals/")
		(sheetfile "peripherals.kicad_sch")
		(attr smd)
		(fp_rect
			(start -0.925 -0.47)
			(end 0.925 0.47)
			(stroke
				(width 0.05)
				(type default)
			)
			(fill no)
			(layer "F.CrtYd")
		)
		(fp_line
			(start 0.504 0.248)
			(end -0.494 0.248)
			(stroke
				(width 0.15)
				(type solid)
			)
			(layer "F.Fab")
		)
		(fp_line
			(start 0.504 -0.25)
			(end 0.504 0.248)
			(stroke
				(width 0.15)
				(type solid)
			)
			(layer "F.Fab")
		)
		(fp_line
			(start -0.494 0.248)
			(end -0.494 -0.25)
			(stroke
				(width 0.15)
				(type solid)
			)
			(layer "F.Fab")
		)
		(fp_line
			(start -0.494 -0.25)
			(end 0.504 -0.25)
			(stroke
				(width 0.15)
				(type solid)
			)
			(layer "F.Fab")
		)
		(fp_text user "${REFERENCE}"
			(at -0.939 4.599 0)
			(layer "F.Fab")
			(effects
				(font
					(size 0.7 0.7)
					(thickness 0.15)
				)
				(justify right top)
			)
		)
		(fp_text user "Author: Antmicro"
			(at -0.939 3.399 0)
			(layer "F.Fab")
			(effects
				(font
					(size 0.7 0.7)
					(thickness 0.15)
				)
				(justify right top)
			)
		)
		(fp_text user "License: Apache-2.0"
			(at -0.939 5.799 0)
			(layer "F.Fab")
			(effects
				(font
					(size 0.7 0.7)
					(thickness 0.15)
				)
				(justify right top)
			)
		)
		(pad "1" smd roundrect
			(at -0.48 0 180)
			(size 0.59 0.64)
			(layers "F.Cu" "F.Mask" "F.Paste")
			(roundrect_rratio 0.25)
			(net 110 "Net-(C817-Pad1)")
			(pintype "passive")
		)
		(pad "2" smd roundrect
			(at 0.48 0 180)
			(size 0.59 0.64)
			(layers "F.Cu" "F.Mask" "F.Paste")
			(roundrect_rratio 0.25)
			(net 106 "Net-(C814-Pad2)")
			(pintype "passive")
		)
	)
	(footprint "antmicro-footprints:C_0402_1005Metric"
		(layer "F.Cu")
		(at 76.242962 174.3665)
		(descr "Capacitor SMD 0402")
		(tags "capacitor SMD 0402")
		(property "Reference" "C806"
			(at 5.155 -0.98 0)
			(layer "F.SilkS")
			(effects
				(font
					(size 0.7 0.7)
					(thickness 0.15)
				)
				(justify left bottom)
			)
		)
		(property "Value" "C_2u2_0402"
			(at -1.022927 2.155213 0)
			(layer "F.Fab")
			(effects
				(font
					(size 0.7 0.7)
					(thickness 0.15)
				)
				(justify left bottom)
			)
		)
		(property "Datasheet" "https://product.tdk.com/en/search/capacitor/ceramic/mlcc/info?part_no=C1005X5R1A225K050BC"
			(at 0 0 0)
			(layer "F.Fab")
			(hide yes)
			(effects
				(font
					(size 1.27 1.27)
					(thickness 0.15)
				)
			)
		)
		(property "MPN" "C1005X5R1A225K050BC"
			(at 0 0 0)
			(unlocked yes)
			(layer "F.Fab")
			(hide yes)
			(effects
				(font
					(size 1 1)
					(thickness 0.15)
				)
			)
		)
		(property "Manufacturer" "TDK"
			(at 0 0 0)
			(unlocked yes)
			(layer "F.Fab")
			(hide yes)
			(effects
				(font
					(size 1 1)
					(thickness 0.15)
				)
			)
		)
		(property "License" "Apache-2.0"
			(at 0 0 0)
			(unlocked yes)
			(layer "F.Fab")
			(hide yes)
			(effects
				(font
					(size 1 1)
					(thickness 0.15)
				)
			)
		)
		(property "Author" "Antmicro"
			(at 0 0 0)
			(unlocked yes)
			(layer "F.Fab")
			(hide yes)
			(effects
				(font
					(size 1 1)
					(thickness 0.15)
				)
			)
		)
		(property "Val" "2u2"
			(at 0 0 0)
			(unlocked yes)
			(layer "F.Fab")
			(hide yes)
			(effects
				(font
					(size 1 1)
					(thickness 0.15)
				)
			)
		)
		(property "Voltage" ""
			(at 0 0 0)
			(unlocked yes)
			(layer "F.Fab")
			(hide yes)
			(effects
				(font
					(size 1 1)
					(thickness 0.15)
				)
			)
		)
		(property "Dielectric" ""
			(at 0 0 0)
			(unlocked yes)
			(layer "F.Fab")
			(hide yes)
			(effects
				(font
					(size 1 1)
					(thickness 0.15)
				)
			)
		)
		(sheetname "/Peripherals/")
		(sheetfile "peripherals.kicad_sch")
		(attr smd)
		(fp_rect
			(start -0.925 -0.47)
			(end 0.925 0.47)
			(stroke
				(width 0.05)
				(type default)
			)
			(fill no)
			(layer "F.CrtYd")
		)
		(fp_line
			(start -0.494 -0.25)
			(end 0.504 -0.25)
			(stroke
				(width 0.15)
				(type solid)
			)
			(layer "F.Fab")
		)
		(fp_line
			(start -0.494 0.248)
			(end -0.494 -0.25)
			(stroke
				(width 0.15)
				(type solid)
			)
			(layer "F.Fab")
		)
		(fp_line
			(start 0.504 -0.25)
			(end 0.504 0.248)
			(stroke
				(width 0.15)
				(type solid)
			)
			(layer "F.Fab")
		)
		(fp_line
			(start 0.504 0.248)
			(end -0.494 0.248)
			(stroke
				(width 0.15)
				(type solid)
			)
			(layer "F.Fab")
		)
		(fp_text user "${REFERENCE}"
			(at -0.939 4.599 0)
			(layer "F.Fab")
			(effects
				(font
					(size 0.7 0.7)
					(thickness 0.15)
				)
				(justify left bottom)
			)
		)
		(fp_text user "Author: Antmicro"
			(at -0.939 3.399 0)
			(layer "F.Fab")
			(effects
				(font
					(size 0.7 0.7)
					(thickness 0.15)
				)
				(justify left bottom)
			)
		)
		(fp_text user "License: Apache-2.0"
			(at -0.939 5.799 0)
			(layer "F.Fab")
			(effects
				(font
					(size 0.7 0.7)
					(thickness 0.15)
				)
				(justify left bottom)
			)
		)
		(pad "1" smd roundrect
			(at -0.48 0)
			(size 0.59 0.64)
			(layers "F.Cu" "F.Mask" "F.Paste")
			(roundrect_rratio 0.25)
			(net 93 "Net-(U801-V_{DD(A)})")
			(pintype "passive")
		)
		(pad "2" smd roundrect
			(at 0.48 0)
			(size 0.59 0.64)
			(layers "F.Cu" "F.Mask" "F.Paste")
			(roundrect_rratio 0.25)
			(net 3 "GND")
			(pintype "passive")
		)
	)
	(footprint "antmicro-footprints:R_0402_1005Metric"
		(layer "F.Cu")
		(at 46.542962 129.7915)
		(descr "Resistor SMD 0402")
		(tags "resistor SMD 0402")
		(property "Reference" "R405"
			(at -3.975 0.35 0)
			(layer "F.SilkS")
			(effects
				(font
					(size 0.7 0.7)
					(thickness 0.15)
				)
				(justify left bottom)
			)
		)
		(property "Value" "R_1k2_0402"
			(at -1.011843 1.772047 0)
			(layer "F.Fab")
			(effects
				(font
					(size 0.7 0.7)
					(thickness 0.15)
				)
				(justify left bottom)
			)
		)
		(property "Datasheet" "https://www.bourns.com/docs/product-datasheets/cr.pdf"
			(at 0 0 0)
			(layer "F.Fab")
			(hide yes)
			(effects
				(font
					(size 1.27 1.27)
					(thickness 0.15)
				)
			)
		)
		(property "Manufacturer" "Bourns"
			(at 0 0 0)
			(unlocked yes)
			(layer "F.Fab")
			(hide yes)
			(effects
				(font
					(size 1 1)
					(thickness 0.15)
				)
			)
		)
		(property "MPN" "CR0402-FX-1201GLF"
			(at 0 0 0)
			(unlocked yes)
			(layer "F.Fab")
			(hide yes)
			(effects
				(font
					(size 1 1)
					(thickness 0.15)
				)
			)
		)
		(property "Val" "1k2"
			(at 0 0 0)
			(unlocked yes)
			(layer "F.Fab")
			(hide yes)
			(effects
				(font
					(size 1 1)
					(thickness 0.15)
				)
			)
		)
		(property "License" "Apache-2.0"
			(at 0 0 0)
			(unlocked yes)
			(layer "F.Fab")
			(hide yes)
			(effects
				(font
					(size 1 1)
					(thickness 0.15)
				)
			)
		)
		(property "Author" "Antmicro"
			(at 0 0 0)
			(unlocked yes)
			(layer "F.Fab")
			(hide yes)
			(effects
				(font
					(size 1 1)
					(thickness 0.15)
				)
			)
		)
		(property "Tolerance" "1%"
			(at 0 0 0)
			(unlocked yes)
			(layer "F.Fab")
			(hide yes)
			(effects
				(font
					(size 1 1)
					(thickness 0.15)
				)
			)
		)
		(sheetname "/Ethernet/")
		(sheetfile "ethernet.kicad_sch")
		(attr smd)
		(fp_rect
			(start -0.925 -0.47)
			(end 0.925 0.47)
			(stroke
				(width 0.05)
				(type default)
			)
			(fill no)
			(layer "F.CrtYd")
		)
		(fp_rect
			(start -0.5 -0.25)
			(end 0.5 0.25)
			(stroke
				(width 0.15)
				(type solid)
			)
			(fill no)
			(layer "F.Fab")
		)
		(fp_text user "Author: Antmicro"
			(at -0.95 4.169 0)
			(layer "F.Fab")
			(effects
				(font
					(size 0.7 0.7)
					(thickness 0.15)
				)
				(justify left bottom)
			)
		)
		(fp_text user "License: Apache-2.0"
			(at -0.95 5.169 0)
			(layer "F.Fab")
			(effects
				(font
					(size 0.7 0.7)
					(thickness 0.15)
				)
				(justify left bottom)
			)
		)
		(fp_text user "${REFERENCE}"
			(at -0.95 3.168 0)
			(layer "F.Fab")
			(effects
				(font
					(size 0.7 0.7)
					(thickness 0.15)
				)
				(justify left bottom)
			)
		)
		(pad "1" smd roundrect
			(at -0.48 0)
			(size 0.59 0.64)
			(layers "F.Cu" "F.Mask" "F.Paste")
			(roundrect_rratio 0.25)
			(net 90 "/Ethernet/VSS")
			(pintype "passive")
		)
		(pad "2" smd roundrect
			(at 0.48 0)
			(size 0.59 0.64)
			(layers "F.Cu" "F.Mask" "F.Paste")
			(roundrect_rratio 0.25)
			(net 360 "/Ethernet/CLSB")
			(pintype "passive")
		)
	)
	(footprint "antmicro-footprints:TP_SMD_0.75mm"
		(layer "F.Cu")
		(at 117.652962 137.7915 -90)
		(property "Reference" "TP307"
			(at 0.425 -3.845 180)
			(layer "F.SilkS")
			(effects
				(font
					(size 0.7 0.7)
					(thickness 0.15)
				)
				(justify right bottom)
			)
		)
		(property "Value" "TP_0.75mm_SMD"
			(at 0 1.2 90)
			(layer "F.Fab")
			(effects
				(font
					(size 0.7 0.7)
					(thickness 0.15)
				)
				(justify right bottom)
			)
		)
		(property "MPN" ""
			(at 0 0 270)
			(unlocked yes)
			(layer "F.Fab")
			(hide yes)
			(effects
				(font
					(size 1 1)
					(thickness 0.15)
				)
			)
		)
		(property "Manufacturer" ""
			(at 0 0 270)
			(unlocked yes)
			(layer "F.Fab")
			(hide yes)
			(effects
				(font
					(size 1 1)
					(thickness 0.15)
				)
			)
		)
		(property "Author" "Antmicro"
			(at 0 0 270)
			(unlocked yes)
			(layer "F.Fab")
			(hide yes)
			(effects
				(font
					(size 1 1)
					(thickness 0.15)
				)
			)
		)
		(property "License" "Apache-2.0"
			(at 0 0 270)
			(unlocked yes)
			(layer "F.Fab")
			(hide yes)
			(effects
				(font
					(size 1 1)
					(thickness 0.15)
				)
			)
		)
		(sheetname "/Supply/")
		(sheetfile "supply.kicad_sch")
		(attr exclude_from_pos_files exclude_from_bom)
		(fp_circle
			(center 0 0)
			(end 0.475 0)
			(stroke
				(width 0.05)
				(type default)
			)
			(fill no)
			(layer "F.CrtYd")
		)
		(fp_text user "License: Apache-2.0"
			(at -0.4 5.101 270)
			(layer "F.Fab")
			(effects
				(font
					(size 0.7 0.7)
					(thickness 0.15)
				)
				(justify left bottom)
			)
		)
		(fp_text user "${REFERENCE}"
			(at -0.4 2.7 270)
			(layer "F.Fab")
			(effects
				(font
					(size 0.7 0.7)
					(thickness 0.15)
				)
				(justify left bottom)
			)
		)
		(fp_text user "Author: Antmicro"
			(at -0.4 3.901 270)
			(layer "F.Fab")
			(effects
				(font
					(size 0.7 0.7)
					(thickness 0.15)
				)
				(justify left bottom)
			)
		)
		(pad "1" smd circle
			(at 0 0 270)
			(size 0.75 0.75)
			(layers "F.Cu" "F.Mask")
			(net 65 "3V3_SSD")
			(pinfunction "1")
			(pintype "passive")
		)
	)
	(footprint "antmicro-footprints:TP_SMD_0.75mm"
		(layer "F.Cu")
		(at 74.767962 159.6665 -90)
		(property "Reference" "TP305"
			(at -1.65 -1.25 270)
			(layer "F.SilkS")
			(effects
				(font
					(size 0.7 0.7)
					(thickness 0.15)
				)
				(justify right bottom)
			)
		)
		(property "Value" "TP_0.75mm_SMD"
			(at 0 1.2 90)
			(layer "F.Fab")
			(effects
				(font
					(size 0.7 0.7)
					(thickness 0.15)
				)
				(justify right bottom)
			)
		)
		(property "MPN" ""
			(at 0 0 270)
			(unlocked yes)
			(layer "F.Fab")
			(hide yes)
			(effects
				(font
					(size 1 1)
					(thickness 0.15)
				)
			)
		)
		(property "Manufacturer" ""
			(at 0 0 270)
			(unlocked yes)
			(layer "F.Fab")
			(hide yes)
			(effects
				(font
					(size 1 1)
					(thickness 0.15)
				)
			)
		)
		(property "Author" "Antmicro"
			(at 0 0 270)
			(unlocked yes)
			(layer "F.Fab")
			(hide yes)
			(effects
				(font
					(size 1 1)
					(thickness 0.15)
				)
			)
		)
		(property "License" "Apache-2.0"
			(at 0 0 270)
			(unlocked yes)
			(layer "F.Fab")
			(hide yes)
			(effects
				(font
					(size 1 1)
					(thickness 0.15)
				)
			)
		)
		(sheetname "/Supply/")
		(sheetfile "supply.kicad_sch")
		(attr exclude_from_pos_files exclude_from_bom)
		(fp_circle
			(center 0 0)
			(end 0.475 0)
			(stroke
				(width 0.05)
				(type default)
			)
			(fill no)
			(layer "F.CrtYd")
		)
		(fp_text user "Author: Antmicro"
			(at -0.4 3.901 270)
			(layer "F.Fab")
			(effects
				(font
					(size 0.7 0.7)
					(thickness 0.15)
				)
				(justify left bottom)
			)
		)
		(fp_text user "${REFERENCE}"
			(at -0.4 2.7 270)
			(layer "F.Fab")
			(effects
				(font
					(size 0.7 0.7)
					(thickness 0.15)
				)
				(justify left bottom)
			)
		)
		(fp_text user "License: Apache-2.0"
			(at -0.4 5.101 270)
			(layer "F.Fab")
			(effects
				(font
					(size 0.7 0.7)
					(thickness 0.15)
				)
				(justify left bottom)
			)
		)
		(pad "1" smd circle
			(at 0 0 270)
			(size 0.75 0.75)
			(layers "F.Cu" "F.Mask")
			(net 10 "+5V")
			(pinfunction "1")
			(pintype "passive")
		)
	)
)
